# SCM (Grand Teton) — schematic netlist excerpt (pin names and nets, part order shuffled) for the footprints in the layout excerpt that follows; sources: Cadence DE-HDL packaged netlist, KiCad conversion of 12092022_DA0F0TMDCD0_F0T_Management_Board_D_brd_V3_OCP.brd

R36  Q_RES  33.2 1% CHIP  pkg 0402LF  page 10 : A = SMB_BMC_MM14_SCL ; B = SMB_BMC_MM14_R1_SCL
C219  Q_CAP  0.1UF 25V 10% X7R  pkg 0402  page 29 : A = P3V3_AUX ; B = GND

(kicad_pcb
	(version 20260206)
	(generator "pcbnew")
	(generator_version "10.0")
	(general
		(thickness 1.6)
		(legacy_teardrops no)
	)
	(paper "A4")
	(title_block
		(title "12092022_DA0F0TMDCD0_F0T_Management_Board_D_brd_V3_OCP.brd")
		(comment 1 "Grand Teton / footprints 1424-1425 of 1440")
	)
	(layers
		(0 "F.Cu" signal "TOP")
		(4 "In1.Cu" signal "GND")
		(6 "In2.Cu" signal "IN1")
		(8 "In3.Cu" signal "GND1")
		(10 "In4.Cu" signal "IN2")
		(12 "In5.Cu" signal "VCC")
		(14 "In6.Cu" signal "VCC1")
		(16 "In7.Cu" signal "IN3")
		(18 "In8.Cu" signal "GND2")
		(20 "In9.Cu" signal "IN4")
		(22 "In10.Cu" signal "GND3")
		(2 "B.Cu" signal "BOTTOM")
		(9 "F.Adhes" user "F.Adhesive")
		(11 "B.Adhes" user "B.Adhesive")
		(13 "F.Paste" user "Package Geometry/Pastemask Top")
		(15 "B.Paste" user "Package Geometry/Pastemask Bottom")
		(5 "F.SilkS" user "Ref Des/Silkscreen Top")
		(7 "B.SilkS" user "Ref Des/Silkscreen Bottom")
		(1 "F.Mask" user "Board Geometry/Soldermask Top")
		(3 "B.Mask" user "Board Geometry/Soldermask Bottom")
		(17 "Dwgs.User" user "User.Drawings")
		(19 "Cmts.User" user "User.Comments")
		(21 "Eco1.User" user "User.Eco1")
		(23 "Eco2.User" user "User.Eco2")
		(25 "Edge.Cuts" user "Board Geometry/Outline")
		(27 "Margin" user)
		(31 "F.CrtYd" user "Package Geometry/Place Bound Top")
		(29 "B.CrtYd" user "Package Geometry/Place Bound Bottom")
		(35 "F.Fab" user "Ref Des/Assembly Top")
		(33 "B.Fab" user "Ref Des/Assembly Bottom")
	)
	(footprint ""
		(layer "B.Cu")
		(at 67.4116 -106.4387 -90)
		(property "Reference" "R36"
			(at 0 0 90)
			(layer "B.SilkS")
			(hide yes)
			(effects
				(font
					(size 1.27 1.27)
				)
				(justify mirror)
			)
		)
		(property "Value" ""
			(at 0 0 90)
			(layer "B.Fab")
			(effects
				(font
					(size 1.27 1.27)
				)
				(justify mirror)
			)
		)
		(duplicate_pad_numbers_are_jumpers no)
		(fp_line
			(start -0.7874 0.4064)
			(end 0.7874 0.4064)
			(stroke
				(width 0.1524)
				(type default)
			)
			(layer "B.SilkS")
		)
		(fp_line
			(start 0.7874 0.4064)
			(end 0.7874 -0.4064)
			(stroke
				(width 0.1524)
				(type default)
			)
			(layer "B.SilkS")
		)
		(fp_line
			(start -0.7874 -0.4064)
			(end -0.7874 0.4064)
			(stroke
				(width 0.1524)
				(type default)
			)
			(layer "B.SilkS")
		)
		(fp_line
			(start 0.7874 -0.4064)
			(end -0.7874 -0.4064)
			(stroke
				(width 0.1524)
				(type default)
			)
			(layer "B.SilkS")
		)
		(fp_line
			(start -0.67945 0.3048)
			(end -0.120396 0.3048)
			(stroke
				(width 0.1)
				(type default)
			)
			(layer "B.Fab")
		)
		(fp_line
			(start -0.120396 0.3048)
			(end -0.120396 0.2794)
			(stroke
				(width 0.1)
				(type default)
			)
			(layer "B.Fab")
		)
		(fp_line
			(start 0.12065 0.3048)
			(end 0.67945 0.3048)
			(stroke
				(width 0.1)
				(type default)
			)
			(layer "B.Fab")
		)
		(fp_line
			(start 0.67945 0.3048)
			(end 0.67945 -0.305054)
			(stroke
				(width 0.1)
				(type default)
			)
			(layer "B.Fab")
		)
		(fp_line
			(start -0.120396 0.2794)
			(end 0.12065 0.2794)
			(stroke
				(width 0.1)
				(type default)
			)
			(layer "B.Fab")
		)
		(fp_line
			(start 0.12065 0.2794)
			(end 0.12065 0.3048)
			(stroke
				(width 0.1)
				(type default)
			)
			(layer "B.Fab")
		)
		(fp_line
			(start -0.12065 -0.2794)
			(end -0.12065 -0.3048)
			(stroke
				(width 0.1)
				(type default)
			)
			(layer "B.Fab")
		)
		(fp_line
			(start 0.12065 -0.2794)
			(end -0.12065 -0.2794)
			(stroke
				(width 0.1)
				(type default)
			)
			(layer "B.Fab")
		)
		(fp_line
			(start -0.67945 -0.3048)
			(end -0.67945 0.3048)
			(stroke
				(width 0.1)
				(type default)
			)
			(layer "B.Fab")
		)
		(fp_line
			(start -0.12065 -0.3048)
			(end -0.67945 -0.3048)
			(stroke
				(width 0.1)
				(type default)
			)
			(layer "B.Fab")
		)
		(fp_line
			(start 0.12065 -0.305054)
			(end 0.12065 -0.2794)
			(stroke
				(width 0.1)
				(type default)
			)
			(layer "B.Fab")
		)
		(fp_line
			(start 0.67945 -0.305054)
			(end 0.12065 -0.305054)
			(stroke
				(width 0.1)
				(type default)
			)
			(layer "B.Fab")
		)
		(pad "1" smd circle
			(at 0.40005 0 90)
			(size 0 0)
			(layers "B.Cu" "B.Mask" "B.Paste")
			(net "SMB_BMC_MM14_SCL")
		)
		(pad "2" smd circle
			(at -0.40005 0 90)
			(size 0 0)
			(layers "B.Cu" "B.Mask" "B.Paste")
			(net "SMB_BMC_MM14_R1_SCL")
		)
	)
	(footprint ""
		(layer "B.Cu")
		(at 45.085 -92.5322 -90)
		(property "Reference" "C219"
			(at 0 0 90)
			(layer "B.SilkS")
			(hide yes)
			(effects
				(font
					(size 1.27 1.27)
				)
				(justify mirror)
			)
		)
		(property "Value" ""
			(at 0 0 90)
			(layer "B.Fab")
			(effects
				(font
					(size 1.27 1.27)
				)
				(justify mirror)
			)
		)
		(duplicate_pad_numbers_are_jumpers no)
		(fp_line
			(start -0.7874 0.4064)
			(end 0.7874 0.4064)
			(stroke
				(width 0.1524)
				(type default)
			)
			(layer "B.SilkS")
		)
		(fp_line
			(start 0.7874 0.4064)
			(end 0.7874 -0.4064)
			(stroke
				(width 0.1524)
				(type default)
			)
			(layer "B.SilkS")
		)
		(fp_line
			(start -0.7874 -0.4064)
			(end -0.7874 0.4064)
			(stroke
				(width 0.1524)
				(type default)
			)
			(layer "B.SilkS")
		)
		(fp_line
			(start 0.7874 -0.4064)
			(end -0.7874 -0.4064)
			(stroke
				(width 0.1524)
				(type default)
			)
			(layer "B.SilkS")
		)
		(fp_line
			(start -0.67945 0.3048)
			(end -0.120396 0.3048)
			(stroke
				(width 0.1)
				(type default)
			)
			(layer "B.Fab")
		)
		(fp_line
			(start -0.120396 0.3048)
			(end -0.120396 0.2794)
			(stroke
				(width 0.1)
				(type default)
			)
			(layer "B.Fab")
		)
		(fp_line
			(start 0.12065 0.3048)
			(end 0.67945 0.3048)
			(stroke
				(width 0.1)
				(type default)
			)
			(layer "B.Fab")
		)
		(fp_line
			(start 0.67945 0.3048)
			(end 0.67945 -0.305054)
			(stroke
				(width 0.1)
				(type default)
			)
			(layer "B.Fab")
		)
		(fp_line
			(start -0.120396 0.2794)
			(end 0.12065 0.2794)
			(stroke
				(width 0.1)
				(type default)
			)
			(layer "B.Fab")
		)
		(fp_line
			(start 0.12065 0.2794)
			(end 0.12065 0.3048)
			(stroke
				(width 0.1)
				(type default)
			)
			(layer "B.Fab")
		)
		(fp_line
			(start -0.12065 -0.2794)
			(end -0.12065 -0.3048)
			(stroke
				(width 0.1)
				(type default)
			)
			(layer "B.Fab")
		)
		(fp_line
			(start 0.12065 -0.2794)
			(end -0.12065 -0.2794)
			(stroke
				(width 0.1)
				(type default)
			)
			(layer "B.Fab")
		)
		(fp_line
			(start -0.67945 -0.3048)
			(end -0.67945 0.3048)
			(stroke
				(width 0.1)
				(type default)
			)
			(layer "B.Fab")
		)
		(fp_line
			(start -0.12065 -0.3048)
			(end -0.67945 -0.3048)
			(stroke
				(width 0.1)
				(type default)
			)
			(layer "B.Fab")
		)
		(fp_line
			(start 0.12065 -0.305054)
			(end 0.12065 -0.2794)
			(stroke
				(width 0.1)
				(type default)
			)
			(layer "B.Fab")
		)
		(fp_line
			(start 0.67945 -0.305054)
			(end 0.12065 -0.305054)
			(stroke
				(width 0.1)
				(type default)
			)
			(layer "B.Fab")
		)
		(pad "1" smd circle
			(at 0.40005 0 90)
			(size 0 0)
			(layers "B.Cu" "B.Mask" "B.Paste")
			(net "P3V3_AUX")
		)
		(pad "2" smd circle
			(at -0.40005 0 90)
			(size 0 0)
			(layers "B.Cu" "B.Mask" "B.Paste")
			(net "GND")
		)
	)
)
